FILE_TYPE = CONNECTIVITY;
{Allegro Design Entry HDL 16.6-p007 (v16-6-112F) 10/10/2012}
"PAGE_NUMBER" = 270;
0"NC";
1"GND\g";
2"GND\g";
3"GND\g";
4"GND\g";
5"GND\g";
6"GND\g";
7"GND\g";
8"GND\g";
9"GND\g";
10"GND\g";
11"GND\g";
12"GND\g";
13"L14_85OHM_5INCH_DP";
14"L14_85OHM_5INCH_DN";
15"L12_85OHM_5INCH_DN";
16"L12_85OHM_5INCH_DP";
17"L12_85OHM_5INCH_DN";
18"L12_85OHM_5INCH_DP";
19"L14_85OHM_5INCH_DP";
20"L14_85OHM_5INCH_DN";
21"L10_85OHM_5INCH_DN";
22"L10_85OHM_5INCH_DP";
23"L10_85OHM_5INCH_DN";
24"L10_85OHM_5INCH_DP";
25"L5_85OHM_5INCH_DP";
26"L5_85OHM_5INCH_DN";
27"L3_85OHM_5INCH_DP";
28"L3_85OHM_5INCH_DN";
29"L3_85OHM_5INCH_DN";
30"L1_85OHM_5INCH_DP";
31"L1_85OHM_5INCH_DN";
32"L1_85OHM_5INCH_DN";
33"L1_85OHM_5INCH_DP";
34"L3_85OHM_5INCH_DP";
35"L5_85OHM_5INCH_DN";
36"L5_85OHM_5INCH_DP";
%"TEST-PAD-12P-1-GP-U"
"1","(-8825,5975)","0","w_hdl","I1";
;
CDS_SEC"1"
CDS_LOCATION"T1D1"
LOCATION"T1D1"
VALUE"TEST-PAD-12P-1-GP-U"
CDS_LMAN_SYM_OUTLINE"-75,375,75,-375"
CDS_LIB"w_hdl"
PART_NUMBER"ZZ.00PAD.MJ1"
PACK_TYPE"DISCRET-GB1"
SEC"1"
SEC_TYPE"DISCRET-GB1";
"DN"
$PN"2"32;
"DP"
$PN"1"33;
"GND<9>"
$PN"12"6;
"GND<8>"
$PN"11"6;
"GND<7>"
$PN"10"6;
"GND<6>"
$PN"9"6;
"GND<5>"
$PN"8"6;
"GND<4>"
$PN"7"6;
"GND<3>"
$PN"6"6;
"GND<2>"
$PN"5"6;
"GND<1>"
$PN"4"6;
"GND<0>"
$PN"3"6;
%"GND"
"1","(-7600,3700)","0","mstr_symbols","I10";
;
VOLTAGE"0.0V"
SIZE"1B"
BODY_TYPE"PLUMBING"
HDL_POWER"GND"
CDS_LIB"mstr_symbols";
"A\NAC"1;
%"GND"
"1","(-8450,3700)","0","mstr_symbols","I11";
;
CDS_LIB"mstr_symbols"
HDL_POWER"GND"
BODY_TYPE"PLUMBING"
SIZE"1B"
VOLTAGE"0.0V";
"A\NAC"2;
%"TEST-PAD-12P-1-GP-U"
"1","(-8825,4075)","0","w_hdl","I12";
;
CDS_SEC"1"
CDS_LOCATION"T1D5"
VALUE"TEST-PAD-12P-1-GP-U"
LOCATION"T1D5"
SEC_TYPE"DISCRET-GB1"
SEC"1"
PACK_TYPE"DISCRET-GB1"
PART_NUMBER"ZZ.00PAD.MJ1"
CDS_LIB"w_hdl"
CDS_LMAN_SYM_OUTLINE"-75,375,75,-375";
"DN"
$PN"2"35;
"DP"
$PN"1"36;
"GND<9>"
$PN"12"2;
"GND<8>"
$PN"11"2;
"GND<7>"
$PN"10"2;
"GND<6>"
$PN"9"2;
"GND<5>"
$PN"8"2;
"GND<4>"
$PN"7"2;
"GND<3>"
$PN"6"2;
"GND<2>"
$PN"5"2;
"GND<1>"
$PN"4"2;
"GND<0>"
$PN"3"2;
%"TEST-PAD-12P-1-GP-U"
"1","(-4775,6000)","2","w_hdl","I13";
;
CDS_SEC"1"
CDS_LOCATION"T1D8"
LOCATION"T1D8"
VALUE"TEST-PAD-12P-1-GP-U"
CDS_LMAN_SYM_OUTLINE"-75,375,75,-375"
CDS_LIB"w_hdl"
PART_NUMBER"ZZ.00PAD.MJ1"
PACK_TYPE"DISCRET-GB1"
SEC"1"
SEC_TYPE"DISCRET-GB1";
"DN"
$PN"2"24;
"DP"
$PN"1"23;
"GND<9>"
$PN"12"3;
"GND<8>"
$PN"11"3;
"GND<7>"
$PN"10"3;
"GND<6>"
$PN"9"3;
"GND<5>"
$PN"8"3;
"GND<4>"
$PN"7"3;
"GND<3>"
$PN"6"3;
"GND<2>"
$PN"5"3;
"GND<1>"
$PN"4"3;
"GND<0>"
$PN"3"3;
%"GND"
"1","(-5150,5625)","0","mstr_symbols","I14";
;
CDS_LIB"mstr_symbols"
HDL_POWER"GND"
BODY_TYPE"PLUMBING"
SIZE"1B"
VOLTAGE"0.0V";
"A\NAC"3;
%"GND"
"1","(-6000,5625)","0","mstr_symbols","I15";
;
VOLTAGE"0.0V"
SIZE"1B"
BODY_TYPE"PLUMBING"
HDL_POWER"GND"
CDS_LIB"mstr_symbols";
"A\NAC"4;
%"TEST-PAD-12P-1-GP-U"
"1","(-6375,6000)","0","w_hdl","I16";
;
CDS_SEC"1"
CDS_LOCATION"T1D7"
VALUE"TEST-PAD-12P-1-GP-U"
LOCATION"T1D7"
CDS_LMAN_SYM_OUTLINE"-75,375,75,-375"
CDS_LIB"w_hdl"
PART_NUMBER"ZZ.00PAD.MJ1"
PACK_TYPE"DISCRET-GB1"
SEC"1"
SEC_TYPE"DISCRET-GB1";
"DN"
$PN"2"21;
"DP"
$PN"1"22;
"GND<9>"
$PN"12"4;
"GND<8>"
$PN"11"4;
"GND<7>"
$PN"10"4;
"GND<6>"
$PN"9"4;
"GND<5>"
$PN"8"4;
"GND<4>"
$PN"7"4;
"GND<3>"
$PN"6"4;
"GND<2>"
$PN"5"4;
"GND<1>"
$PN"4"4;
"GND<0>"
$PN"3"4;
%"TEST-PAD-12P-1-GP-U"
"1","(-4775,5050)","2","w_hdl","I17";
;
CDS_SEC"1"
CDS_LOCATION"T1D10"
LOCATION"T1D10"
VALUE"TEST-PAD-12P-1-GP-U"
SEC_TYPE"DISCRET-GB1"
SEC"1"
PACK_TYPE"DISCRET-GB1"
PART_NUMBER"ZZ.00PAD.MJ1"
CDS_LIB"w_hdl"
CDS_LMAN_SYM_OUTLINE"-75,375,75,-375";
"DN"
$PN"2"16;
"DP"
$PN"1"15;
"GND<9>"
$PN"12"5;
"GND<8>"
$PN"11"5;
"GND<7>"
$PN"10"5;
"GND<6>"
$PN"9"5;
"GND<5>"
$PN"8"5;
"GND<4>"
$PN"7"5;
"GND<3>"
$PN"6"5;
"GND<2>"
$PN"5"5;
"GND<1>"
$PN"4"5;
"GND<0>"
$PN"3"5;
%"TEST-PAD-12P-1-GP-U"
"1","(-6375,5050)","0","w_hdl","I18";
;
CDS_SEC"1"
CDS_LOCATION"T1D9"
VALUE"TEST-PAD-12P-1-GP-U"
LOCATION"T1D9"
SEC_TYPE"DISCRET-GB1"
SEC"1"
PACK_TYPE"DISCRET-GB1"
PART_NUMBER"ZZ.00PAD.MJ1"
CDS_LIB"w_hdl"
CDS_LMAN_SYM_OUTLINE"-75,375,75,-375";
"DN"
$PN"2"17;
"DP"
$PN"1"18;
"GND<9>"
$PN"12"7;
"GND<8>"
$PN"11"7;
"GND<7>"
$PN"10"7;
"GND<6>"
$PN"9"7;
"GND<5>"
$PN"8"7;
"GND<4>"
$PN"7"7;
"GND<3>"
$PN"6"7;
"GND<2>"
$PN"5"7;
"GND<1>"
$PN"4"7;
"GND<0>"
$PN"3"7;
%"GND"
"1","(-5150,4675)","0","mstr_symbols","I19";
;
VOLTAGE"0.0V"
SIZE"1B"
BODY_TYPE"PLUMBING"
HDL_POWER"GND"
CDS_LIB"mstr_symbols";
"A\NAC"5;
%"GND"
"1","(-8450,5600)","0","mstr_symbols","I2";
;
VOLTAGE"0.0V"
SIZE"1B"
BODY_TYPE"PLUMBING"
HDL_POWER"GND"
CDS_LIB"mstr_symbols";
"A\NAC"6;
%"GND"
"1","(-6000,4675)","0","mstr_symbols","I20";
;
CDS_LIB"mstr_symbols"
HDL_POWER"GND"
BODY_TYPE"PLUMBING"
SIZE"1B"
VOLTAGE"0.0V";
"A\NAC"7;
%"TEST-PAD-12P-1-GP-U"
"1","(-4775,4100)","2","w_hdl","I21";
;
CDS_SEC"1"
CDS_LOCATION"T1D12"
VALUE"TEST-PAD-12P-1-GP-U"
LOCATION"T1D12"
CDS_LMAN_SYM_OUTLINE"-75,375,75,-375"
CDS_LIB"w_hdl"
PART_NUMBER"ZZ.00PAD.MJ1"
PACK_TYPE"DISCRET-GB1"
SEC"1"
SEC_TYPE"DISCRET-GB1";
"DN"
$PN"2"19;
"DP"
$PN"1"20;
"GND<9>"
$PN"12"8;
"GND<8>"
$PN"11"8;
"GND<7>"
$PN"10"8;
"GND<6>"
$PN"9"8;
"GND<5>"
$PN"8"8;
"GND<4>"
$PN"7"8;
"GND<3>"
$PN"6"8;
"GND<2>"
$PN"5"8;
"GND<1>"
$PN"4"8;
"GND<0>"
$PN"3"8;
%"GND"
"1","(-5150,3725)","0","mstr_symbols","I22";
;
CDS_LIB"mstr_symbols"
HDL_POWER"GND"
BODY_TYPE"PLUMBING"
SIZE"1B"
VOLTAGE"0.0V";
"A\NAC"8;
%"GND"
"1","(-6000,3725)","0","mstr_symbols","I23";
;
VOLTAGE"0.0V"
SIZE"1B"
BODY_TYPE"PLUMBING"
HDL_POWER"GND"
CDS_LIB"mstr_symbols";
"A\NAC"9;
%"TEST-PAD-12P-1-GP-U"
"1","(-6375,4100)","0","w_hdl","I24";
;
CDS_SEC"1"
CDS_LOCATION"T1D11"
VALUE"TEST-PAD-12P-1-GP-U"
LOCATION"T1D11"
CDS_LMAN_SYM_OUTLINE"-75,375,75,-375"
CDS_LIB"w_hdl"
PART_NUMBER"ZZ.00PAD.MJ1"
PACK_TYPE"DISCRET-GB1"
SEC"1"
SEC_TYPE"DISCRET-GB1";
"DN"
$PN"2"14;
"DP"
$PN"1"13;
"GND<9>"
$PN"12"9;
"GND<8>"
$PN"11"9;
"GND<7>"
$PN"10"9;
"GND<6>"
$PN"9"9;
"GND<5>"
$PN"8"9;
"GND<4>"
$PN"7"9;
"GND<3>"
$PN"6"9;
"GND<2>"
$PN"5"9;
"GND<1>"
$PN"4"9;
"GND<0>"
$PN"3"9;
%"TEST-PAD-12P-1-GP-U"
"1","(-7225,5975)","2","w_hdl","I3";
;
CDS_SEC"1"
CDS_LOCATION"T1D2"
LOCATION"T1D2"
VALUE"TEST-PAD-12P-1-GP-U"
CDS_LMAN_SYM_OUTLINE"-75,375,75,-375"
CDS_LIB"w_hdl"
PART_NUMBER"ZZ.00PAD.MJ1"
PACK_TYPE"DISCRET-GB1"
SEC"1"
SEC_TYPE"DISCRET-GB1";
"DN"
$PN"2"30;
"DP"
$PN"1"31;
"GND<9>"
$PN"12"10;
"GND<8>"
$PN"11"10;
"GND<7>"
$PN"10"10;
"GND<6>"
$PN"9"10;
"GND<5>"
$PN"8"10;
"GND<4>"
$PN"7"10;
"GND<3>"
$PN"6"10;
"GND<2>"
$PN"5"10;
"GND<1>"
$PN"4"10;
"GND<0>"
$PN"3"10;
%"GND"
"1","(-7600,5600)","0","mstr_symbols","I4";
;
CDS_LIB"mstr_symbols"
HDL_POWER"GND"
BODY_TYPE"PLUMBING"
SIZE"1B"
VOLTAGE"0.0V";
"A\NAC"10;
%"TEST-PAD-12P-1-GP-U"
"1","(-8825,5025)","0","w_hdl","I5";
;
CDS_SEC"1"
CDS_LOCATION"T1D3"
VALUE"TEST-PAD-12P-1-GP-U"
LOCATION"T1D3"
SEC_TYPE"DISCRET-GB1"
SEC"1"
PACK_TYPE"DISCRET-GB1"
PART_NUMBER"ZZ.00PAD.MJ1"
CDS_LIB"w_hdl"
CDS_LMAN_SYM_OUTLINE"-75,375,75,-375";
"DN"
$PN"2"28;
"DP"
$PN"1"34;
"GND<9>"
$PN"12"12;
"GND<8>"
$PN"11"12;
"GND<7>"
$PN"10"12;
"GND<6>"
$PN"9"12;
"GND<5>"
$PN"8"12;
"GND<4>"
$PN"7"12;
"GND<3>"
$PN"6"12;
"GND<2>"
$PN"5"12;
"GND<1>"
$PN"4"12;
"GND<0>"
$PN"3"12;
%"TEST-PAD-12P-1-GP-U"
"1","(-7225,5025)","2","w_hdl","I6";
;
CDS_SEC"1"
CDS_LOCATION"T1D4"
VALUE"TEST-PAD-12P-1-GP-U"
LOCATION"T1D4"
SEC_TYPE"DISCRET-GB1"
SEC"1"
PACK_TYPE"DISCRET-GB1"
PART_NUMBER"ZZ.00PAD.MJ1"
CDS_LIB"w_hdl"
CDS_LMAN_SYM_OUTLINE"-75,375,75,-375";
"DN"
$PN"2"27;
"DP"
$PN"1"29;
"GND<9>"
$PN"12"11;
"GND<8>"
$PN"11"11;
"GND<7>"
$PN"10"11;
"GND<6>"
$PN"9"11;
"GND<5>"
$PN"8"11;
"GND<4>"
$PN"7"11;
"GND<3>"
$PN"6"11;
"GND<2>"
$PN"5"11;
"GND<1>"
$PN"4"11;
"GND<0>"
$PN"3"11;
%"GND"
"1","(-7600,4650)","0","mstr_symbols","I7";
;
VOLTAGE"0.0V"
SIZE"1B"
BODY_TYPE"PLUMBING"
HDL_POWER"GND"
CDS_LIB"mstr_symbols";
"A\NAC"11;
%"GND"
"1","(-8450,4650)","0","mstr_symbols","I8";
;
CDS_LIB"mstr_symbols"
HDL_POWER"GND"
BODY_TYPE"PLUMBING"
SIZE"1B"
VOLTAGE"0.0V";
"A\NAC"12;
%"TEST-PAD-12P-1-GP-U"
"1","(-7225,4075)","2","w_hdl","I9";
;
CDS_SEC"1"
CDS_LOCATION"T1D6"
LOCATION"T1D6"
VALUE"TEST-PAD-12P-1-GP-U"
SEC_TYPE"DISCRET-GB1"
SEC"1"
PACK_TYPE"DISCRET-GB1"
PART_NUMBER"ZZ.00PAD.MJ1"
CDS_LIB"w_hdl"
CDS_LMAN_SYM_OUTLINE"-75,375,75,-375";
"DN"
$PN"2"25;
"DP"
$PN"1"26;
"GND<9>"
$PN"12"1;
"GND<8>"
$PN"11"1;
"GND<7>"
$PN"10"1;
"GND<6>"
$PN"9"1;
"GND<5>"
$PN"8"1;
"GND<4>"
$PN"7"1;
"GND<3>"
$PN"6"1;
"GND<2>"
$PN"5"1;
"GND<1>"
$PN"4"1;
"GND<0>"
$PN"3"1;
END.
